(kicad_pcb
	(version 20260206)
	(generator "pcbnew")
	(generator_version "10.0")
	(general
		(thickness 1.6)
		(legacy_teardrops no)
	)
	(paper "A4")
	(title_block
		(title "v1-chassis-manager — T6M_CM_d_v01_1031_1645.brd")
		(comment 1 "Open CloudServer (Microsoft) / footprints 569-576 of 2512")
	)
	(layers
		(0 "F.Cu" signal "TOP")
		(4 "In1.Cu" signal "GND1")
		(6 "In2.Cu" signal "IN1")
		(8 "In3.Cu" signal "VCC1")
		(10 "In4.Cu" signal "VCC2")
		(12 "In5.Cu" signal "GND2")
		(14 "In6.Cu" signal "IN2")
		(16 "In7.Cu" signal "IN3")
		(18 "In8.Cu" signal "GND3")
		(2 "B.Cu" signal "BOTTOM")
		(9 "F.Adhes" user "F.Adhesive")
		(11 "B.Adhes" user "B.Adhesive")
		(13 "F.Paste" user "Package Geometry/Pastemask Top")
		(15 "B.Paste" user "Package Geometry/Pastemask Bottom")
		(5 "F.SilkS" user "Ref Des/Silkscreen Top")
		(7 "B.SilkS" user "Ref Des/Silkscreen Bottom")
		(1 "F.Mask" user "Board Geometry/Soldermask Top")
		(3 "B.Mask" user "Board Geometry/Soldermask Bottom")
		(17 "Dwgs.User" user "User.Drawings")
		(19 "Cmts.User" user "User.Comments")
		(21 "Eco1.User" user "User.Eco1")
		(23 "Eco2.User" user "User.Eco2")
		(25 "Edge.Cuts" user "Board Geometry/Outline")
		(27 "Margin" user)
		(31 "F.CrtYd" user "Package Geometry/Place Bound Top")
		(29 "B.CrtYd" user "Package Geometry/Place Bound Bottom")
		(35 "F.Fab" user "Ref Des/Assembly Top")
		(33 "B.Fab" user "Ref Des/Assembly Bottom")
	)
	(footprint ""
		(layer "F.Cu")
		(at 157.074616 -138.878056)
		(property "Reference" "C565"
			(at 1.43764 -0.81026 0)
			(unlocked yes)
			(layer "F.SilkS")
			(effects
				(font
					(size 0.7874 0.5842)
					(thickness 0.1524)
				)
				(justify left)
			)
		)
		(property "Value" ""
			(at 0 0 0)
			(layer "F.Fab")
			(effects
				(font
					(size 1.27 1.27)
				)
			)
		)
		(duplicate_pad_numbers_are_jumpers no)
		(fp_line
			(start -0.7874 -0.4064)
			(end 0.7874 -0.4064)
			(stroke
				(width 0.1524)
				(type default)
			)
			(layer "F.SilkS")
		)
		(fp_line
			(start -0.7874 0.4064)
			(end -0.7874 -0.4064)
			(stroke
				(width 0.1524)
				(type default)
			)
			(layer "F.SilkS")
		)
		(fp_line
			(start 0 0.381)
			(end 0 -0.381)
			(stroke
				(width 0.1524)
				(type default)
			)
			(layer "F.SilkS")
		)
		(fp_line
			(start 0.7874 -0.4064)
			(end 0.7874 0.4064)
			(stroke
				(width 0.1524)
				(type default)
			)
			(layer "F.SilkS")
		)
		(fp_line
			(start 0.7874 0.4064)
			(end -0.7874 0.4064)
			(stroke
				(width 0.1524)
				(type default)
			)
			(layer "F.SilkS")
		)
		(fp_poly
			(pts
				(xy -0.5334 0.254) (xy -0.635 0.254) (xy -0.635 0.2286) (xy -0.635 -0.254) (xy -0.5334 -0.254) (xy -0.5334 -0.2794)
				(xy 0.5334 -0.2794) (xy 0.5334 -0.254) (xy 0.635 -0.254) (xy 0.635 0.254) (xy 0.5334 0.254) (xy 0.5334 0.2794)
				(xy -0.508 0.2794) (xy -0.5334 0.2794)
			)
			(stroke
				(width 0)
				(type default)
			)
			(fill no)
			(layer "F.CrtYd")
		)
		(pad "1" smd rect
			(at 0.40005 0)
			(size 0.4572 0.508)
			(layers "F.Cu" "F.Mask" "F.Paste")
			(net "P3V3_STB_NODE1")
		)
		(pad "2" smd rect
			(at -0.40005 0)
			(size 0.4572 0.508)
			(layers "F.Cu" "F.Mask" "F.Paste")
			(net "GND")
		)
	)
	(footprint ""
		(layer "F.Cu")
		(at 166.610538 -12.491974 90)
		(property "Reference" "R1213"
			(at -0.839724 -1.991868 90)
			(unlocked yes)
			(layer "F.SilkS")
			(effects
				(font
					(size 0.7874 0.5842)
					(thickness 0.1524)
				)
				(justify left)
			)
		)
		(property "Value" ""
			(at 0 0 90)
			(layer "F.Fab")
			(effects
				(font
					(size 1.27 1.27)
				)
			)
		)
		(duplicate_pad_numbers_are_jumpers no)
		(fp_line
			(start 0.7874 -0.4064)
			(end 0.7874 0.4064)
			(stroke
				(width 0.1524)
				(type default)
			)
			(layer "F.SilkS")
		)
		(fp_line
			(start -0.7874 -0.4064)
			(end 0.7874 -0.4064)
			(stroke
				(width 0.1524)
				(type default)
			)
			(layer "F.SilkS")
		)
		(fp_line
			(start 0.7874 0.4064)
			(end -0.7874 0.4064)
			(stroke
				(width 0.1524)
				(type default)
			)
			(layer "F.SilkS")
		)
		(fp_line
			(start -0.7874 0.4064)
			(end -0.7874 -0.4064)
			(stroke
				(width 0.1524)
				(type default)
			)
			(layer "F.SilkS")
		)
		(fp_poly
			(pts
				(xy -0.508 0.2794) (xy -0.508 0.2286) (xy -0.635 0.2286) (xy -0.635 -0.254) (xy -0.5334 -0.254)
				(xy -0.5334 -0.2794) (xy 0.5334 -0.2794) (xy 0.5334 -0.254) (xy 0.635 -0.254) (xy 0.635 0.254) (xy 0.5334 0.254)
				(xy 0.5334 0.2794)
			)
			(stroke
				(width 0)
				(type default)
			)
			(fill no)
			(layer "F.CrtYd")
		)
		(pad "1" smd rect
			(at 0.40005 0 90)
			(size 0.4572 0.508)
			(layers "F.Cu" "F.Mask" "F.Paste")
			(net "P3V3_NODE1")
		)
		(pad "2" smd rect
			(at -0.40005 0 90)
			(size 0.4572 0.508)
			(layers "F.Cu" "F.Mask" "F.Paste")
			(net "JTAG_CPLD3_TMS")
		)
	)
	(footprint ""
		(layer "F.Cu")
		(at 56.166766 -161.928556 -90)
		(property "Reference" "C390"
			(at 3.950462 0.292354 90)
			(unlocked yes)
			(layer "F.SilkS")
			(effects
				(font
					(size 0.7874 0.5842)
					(thickness 0.1524)
				)
				(justify left)
			)
		)
		(property "Value" ""
			(at 0 0 270)
			(layer "F.Fab")
			(effects
				(font
					(size 1.27 1.27)
				)
			)
		)
		(duplicate_pad_numbers_are_jumpers no)
		(fp_line
			(start -0.7874 0.4064)
			(end -0.7874 -0.4064)
			(stroke
				(width 0.1524)
				(type default)
			)
			(layer "F.SilkS")
		)
		(fp_line
			(start 0.7874 0.4064)
			(end -0.7874 0.4064)
			(stroke
				(width 0.1524)
				(type default)
			)
			(layer "F.SilkS")
		)
		(fp_line
			(start 0 0.381)
			(end 0 -0.381)
			(stroke
				(width 0.1524)
				(type default)
			)
			(layer "F.SilkS")
		)
		(fp_line
			(start -0.7874 -0.4064)
			(end 0.7874 -0.4064)
			(stroke
				(width 0.1524)
				(type default)
			)
			(layer "F.SilkS")
		)
		(fp_line
			(start 0.7874 -0.4064)
			(end 0.7874 0.4064)
			(stroke
				(width 0.1524)
				(type default)
			)
			(layer "F.SilkS")
		)
		(fp_poly
			(pts
				(xy -0.5334 0.254) (xy -0.635 0.254) (xy -0.635 0.2286) (xy -0.635 -0.254) (xy -0.5334 -0.254) (xy -0.5334 -0.2794)
				(xy 0.5334 -0.2794) (xy 0.5334 -0.254) (xy 0.635 -0.254) (xy 0.635 0.254) (xy 0.5334 0.254) (xy 0.5334 0.2794)
				(xy -0.508 0.2794) (xy -0.5334 0.2794)
			)
			(stroke
				(width 0)
				(type default)
			)
			(fill no)
			(layer "F.CrtYd")
		)
		(pad "1" smd rect
			(at 0.40005 0 270)
			(size 0.4572 0.508)
			(layers "F.Cu" "F.Mask" "F.Paste")
			(net "P3V3_NODE1")
		)
		(pad "2" smd rect
			(at -0.40005 0 270)
			(size 0.4572 0.508)
			(layers "F.Cu" "F.Mask" "F.Paste")
			(net "GND")
		)
	)
	(footprint ""
		(layer "F.Cu")
		(at 83.218528 -95.159068 180)
		(property "Reference" "C108"
			(at -3.723132 -1.801368 0)
			(unlocked yes)
			(layer "F.SilkS")
			(effects
				(font
					(size 0.7874 0.5842)
					(thickness 0.1524)
				)
			)
		)
		(property "Value" ""
			(at 0 0 180)
			(layer "F.Fab")
			(effects
				(font
					(size 1.27 1.27)
				)
			)
		)
		(duplicate_pad_numbers_are_jumpers no)
		(fp_line
			(start 1.2954 0.5842)
			(end -1.2954 0.5842)
			(stroke
				(width 0.1524)
				(type default)
			)
			(layer "F.SilkS")
		)
		(fp_line
			(start 1.2954 -0.5842)
			(end 1.2954 0.5842)
			(stroke
				(width 0.1524)
				(type default)
			)
			(layer "F.SilkS")
		)
		(fp_line
			(start 0 -0.5842)
			(end 0 0.5842)
			(stroke
				(width 0.1524)
				(type default)
			)
			(layer "F.SilkS")
		)
		(fp_line
			(start -1.2954 0.5842)
			(end -1.2954 -0.5842)
			(stroke
				(width 0.1524)
				(type default)
			)
			(layer "F.SilkS")
		)
		(fp_line
			(start -1.2954 -0.5842)
			(end 1.2954 -0.5842)
			(stroke
				(width 0.1524)
				(type default)
			)
			(layer "F.SilkS")
		)
		(fp_poly
			(pts
				(xy 0.8636 -0.4572) (xy 0.8636 -0.3556) (xy 1.143 -0.3556) (xy 1.143 0.3556) (xy 0.8636 0.3556)
				(xy 0.8636 0.4572) (xy -0.8636 0.4572) (xy -0.8636 0.3556) (xy -1.143 0.3556) (xy -1.143 -0.3556)
				(xy -0.8636 -0.3556) (xy -0.8636 -0.4572)
			)
			(stroke
				(width 0)
				(type default)
			)
			(fill no)
			(layer "F.CrtYd")
		)
		(fp_line
			(start 0.884936 0.504952)
			(end -0.884936 0.504952)
			(stroke
				(width 0.1)
				(type default)
			)
			(layer "F.Fab")
		)
		(fp_line
			(start 0.884936 -0.504952)
			(end 0.884936 0.504952)
			(stroke
				(width 0.1)
				(type default)
			)
			(layer "F.Fab")
		)
		(fp_line
			(start -0.884936 0.504952)
			(end -0.884936 -0.504952)
			(stroke
				(width 0.1)
				(type default)
			)
			(layer "F.Fab")
		)
		(fp_line
			(start -0.884936 -0.504952)
			(end 0.884936 -0.504952)
			(stroke
				(width 0.1)
				(type default)
			)
			(layer "F.Fab")
		)
		(pad "1" smd rect
			(at 0.7366 0 270)
			(size 0.7112 0.8128)
			(layers "F.Cu" "F.Mask" "F.Paste")
			(net "P3V3_SUS_NODE1")
		)
		(pad "2" smd rect
			(at -0.7366 0 270)
			(size 0.7112 0.8128)
			(layers "F.Cu" "F.Mask" "F.Paste")
			(net "GND")
		)
	)
	(footprint ""
		(layer "F.Cu")
		(at 5.82549 -152.74798 -90)
		(property "Reference" "R1262"
			(at 2.913888 4.023868 0)
			(unlocked yes)
			(layer "F.SilkS")
			(effects
				(font
					(size 0.7874 0.5842)
					(thickness 0.1524)
				)
				(justify left)
			)
		)
		(property "Value" ""
			(at 0 0 270)
			(layer "F.Fab")
			(effects
				(font
					(size 1.27 1.27)
				)
			)
		)
		(duplicate_pad_numbers_are_jumpers no)
		(fp_line
			(start -0.7874 0.4064)
			(end -0.7874 -0.4064)
			(stroke
				(width 0.1524)
				(type default)
			)
			(layer "F.SilkS")
		)
		(fp_line
			(start 0.7874 0.4064)
			(end -0.7874 0.4064)
			(stroke
				(width 0.1524)
				(type default)
			)
			(layer "F.SilkS")
		)
		(fp_line
			(start -0.7874 -0.4064)
			(end 0.7874 -0.4064)
			(stroke
				(width 0.1524)
				(type default)
			)
			(layer "F.SilkS")
		)
		(fp_line
			(start 0.7874 -0.4064)
			(end 0.7874 0.4064)
			(stroke
				(width 0.1524)
				(type default)
			)
			(layer "F.SilkS")
		)
		(fp_poly
			(pts
				(xy -0.508 0.2794) (xy -0.508 0.2286) (xy -0.635 0.2286) (xy -0.635 -0.254) (xy -0.5334 -0.254)
				(xy -0.5334 -0.2794) (xy 0.5334 -0.2794) (xy 0.5334 -0.254) (xy 0.635 -0.254) (xy 0.635 0.254) (xy 0.5334 0.254)
				(xy 0.5334 0.2794)
			)
			(stroke
				(width 0)
				(type default)
			)
			(fill no)
			(layer "F.CrtYd")
		)
		(pad "1" smd rect
			(at 0.40005 0 270)
			(size 0.4572 0.508)
			(layers "F.Cu" "F.Mask" "F.Paste")
			(net "P3V3_NODE1")
		)
		(pad "2" smd rect
			(at -0.40005 0 270)
			(size 0.4572 0.508)
			(layers "F.Cu" "F.Mask" "F.Paste")
			(net "UART_RI_P5_N")
		)
	)
	(footprint ""
		(layer "F.Cu")
		(at 42.992294 -7.57428 90)
		(property "Reference" "PQ2"
			(at 1.67132 -10.516108 90)
			(unlocked yes)
			(layer "F.SilkS")
			(effects
				(font
					(size 0.7874 0.5842)
					(thickness 0.1524)
				)
				(justify left)
			)
		)
		(property "Value" ""
			(at 0 0 90)
			(layer "F.Fab")
			(effects
				(font
					(size 1.27 1.27)
				)
			)
		)
		(duplicate_pad_numbers_are_jumpers no)
		(fp_line
			(start 4.341876 -0.525018)
			(end 4.341876 -0.294894)
			(stroke
				(width 0.1524)
				(type default)
			)
			(layer "F.SilkS")
		)
		(fp_line
			(start -0.157988 -0.525018)
			(end 4.341876 -0.525018)
			(stroke
				(width 0.1524)
				(type default)
			)
			(layer "F.SilkS")
		)
		(fp_line
			(start -0.157988 -0.294894)
			(end -0.157988 -0.525018)
			(stroke
				(width 0.1524)
				(type default)
			)
			(layer "F.SilkS")
		)
		(fp_line
			(start 4.341876 2.245106)
			(end 4.341876 2.47523)
			(stroke
				(width 0.1524)
				(type default)
			)
			(layer "F.SilkS")
		)
		(fp_line
			(start 4.341876 2.47523)
			(end -0.157988 2.47523)
			(stroke
				(width 0.1524)
				(type default)
			)
			(layer "F.SilkS")
		)
		(fp_line
			(start -0.157988 2.47523)
			(end -0.157988 2.245106)
			(stroke
				(width 0.1524)
				(type default)
			)
			(layer "F.SilkS")
		)
		(fp_poly
			(pts
				(xy -0.339598 0) (xy -1.355598 -0.508) (xy -1.355598 0.508)
			)
			(stroke
				(width 0)
				(type default)
			)
			(fill yes)
			(layer "F.SilkS")
		)
		(fp_poly
			(pts
				(xy -0.157988 -0.525018) (xy -0.157988 -0.294894) (xy -0.346456 -0.294894) (xy -0.346456 2.245106)
				(xy -0.157988 2.245106) (xy -0.157988 2.47523) (xy 4.341876 2.47523) (xy 4.341876 2.245106) (xy 4.530344 2.245106)
				(xy 4.530344 -0.294894) (xy 4.341876 -0.294894) (xy 4.341876 -0.525018)
			)
			(stroke
				(width 0)
				(type default)
			)
			(fill no)
			(layer "F.CrtYd")
		)
		(fp_line
			(start 4.341876 -0.525018)
			(end 4.341876 2.47523)
			(stroke
				(width 0.1)
				(type default)
			)
			(layer "F.Fab")
		)
		(fp_line
			(start -0.157988 -0.525018)
			(end 4.341876 -0.525018)
			(stroke
				(width 0.1)
				(type default)
			)
			(layer "F.Fab")
		)
		(fp_line
			(start 4.341876 2.47523)
			(end -0.157988 2.47523)
			(stroke
				(width 0.1)
				(type default)
			)
			(layer "F.Fab")
		)
		(fp_line
			(start -0.157988 2.47523)
			(end -0.157988 -0.525018)
			(stroke
				(width 0.1)
				(type default)
			)
			(layer "F.Fab")
		)
		(fp_circle
			(center 2.091944 0.975106)
			(end 2.091944 1.104646)
			(stroke
				(width 0.1)
				(type default)
			)
			(fill no)
			(layer "F.Fab")
		)
		(fp_poly
			(pts
				(xy -0.339598 0) (xy -1.355598 -0.508) (xy -1.355598 0.508)
			)
			(stroke
				(width 0)
				(type default)
			)
			(fill yes)
			(layer "F.Fab")
		)
		(pad "1" smd rect
			(at 0 0)
			(size 0.4318 0.5588)
			(layers "F.Cu" "F.Mask" "F.Paste")
			(net "SW_PV_VDDR_NODE1_DRVH")
		)
		(pad "2" smd rect
			(at 0 0.649986)
			(size 0.4318 0.5588)
			(layers "F.Cu" "F.Mask" "F.Paste")
			(net "SW_PV_VDDR_NODE1_VIN_FLT")
		)
		(pad "3" smd rect
			(at 0 1.300226)
			(size 0.4318 0.5588)
			(layers "F.Cu" "F.Mask" "F.Paste")
			(net "SW_PV_VDDR_NODE1_VIN_FLT")
		)
		(pad "4" smd rect
			(at 0 1.950212)
			(size 0.4318 0.5588)
			(layers "F.Cu" "F.Mask" "F.Paste")
			(net "SW_PV_VDDR_NODE1_VIN_FLT")
		)
		(pad "5-6-7" smd custom
			(at 4.181856 1.300226)
			(size 0.143764 0.143764)
			(layers "F.Cu" "F.Mask" "F.Paste")
			(net "GND")
			(options
				(clearance outline)
				(anchor circle)
			)
			(primitives
				(gr_poly
					(pts
						(xy -0.87503 -0.287528) (xy -0.87503 0.287528) (xy 0.87503 0.287528) (xy 0.87503 -0.287528) (xy 0.424942 -0.287528)
						(xy 0.424942 -0.180086) (xy 0.424942 -0.107442) (xy 0.225044 -0.107442) (xy 0.225044 -0.180086)
						(xy 0.225044 -0.287528) (xy -0.225044 -0.287528) (xy -0.225044 -0.180086) (xy -0.225044 -0.107442)
						(xy -0.424942 -0.107442) (xy -0.424942 -0.180086) (xy -0.424942 -0.287528) (xy -0.42545 -0.287528)
					)
					(width 0)
					(fill yes)
				)
			)
		)
		(pad "8" smd rect
			(at 4.181856 0)
			(size 0.4318 0.5588)
			(layers "F.Cu" "F.Mask" "F.Paste")
			(net "SW_PV_VDDR_NODE1_DRVL")
		)
		(pad "D1_EP" smd rect
			(at 0.901954 0.975106 90)
			(size 0.8382 2.5146)
			(layers "F.Cu" "F.Mask" "F.Paste")
			(net "SW_PV_VDDR_NODE1_VIN_FLT")
		)
		(pad "S1/D2_EP" smd rect
			(at 2.675128 0.975106 90)
			(size 2.032 2.5146)
			(layers "F.Cu" "F.Mask" "F.Paste")
			(net "SW_PV_VDDR_NODE1_PH")
		)
		(zone
			(layer "F.Cu")
			(hatch none 0.5)
			(connect_pads
				(clearance 0)
			)
			(min_thickness 0.25)
			(keepout
				(tracks allowed)
				(vias not_allowed)
				(pads allowed)
				(copperpour not_allowed)
				(footprints allowed)
			)
			(placement
				(enabled no)
				(sheetname "")
			)
			(fill
				(thermal_gap 0.5)
				(thermal_bridge_width 0.5)
				(island_removal_mode 0)
			)
			(polygon
				(pts
					(xy 45.456094 -7.92988) (xy 42.484294 -7.92988) (xy 42.484294 -11.40968) (xy 45.456094 -11.40968)
					(xy 45.456094 -8.03148) (xy 45.456094 -8.00608) (xy 45.303694 -8.00608) (xy 45.303694 -8.03148)
					(xy 45.303694 -8.97128) (xy 42.662094 -8.97128) (xy 42.662094 -9.17448) (xy 45.278294 -9.17448)
					(xy 45.278294 -11.33348) (xy 42.636694 -11.33348) (xy 42.636694 -7.98068) (xy 45.456094 -7.98068)
				)
			)
		)
	)
	(footprint ""
		(layer "F.Cu")
		(at 84.171282 -2.67462 180)
		(property "Reference" "PC131"
			(at -1.915922 -1.899666 0)
			(unlocked yes)
			(layer "F.SilkS")
			(effects
				(font
					(size 0.7874 0.5842)
					(thickness 0.1524)
				)
				(justify left)
			)
		)
		(property "Value" ""
			(at 0 0 180)
			(layer "F.Fab")
			(effects
				(font
					(size 1.27 1.27)
				)
			)
		)
		(duplicate_pad_numbers_are_jumpers no)
		(fp_line
			(start 1.905 0.8636)
			(end -1.905 0.8636)
			(stroke
				(width 0.1524)
				(type default)
			)
			(layer "F.SilkS")
		)
		(fp_line
			(start 1.905 -0.8636)
			(end 1.905 0.8636)
			(stroke
				(width 0.1524)
				(type default)
			)
			(layer "F.SilkS")
		)
		(fp_line
			(start 0 0.8382)
			(end 0 -0.8382)
			(stroke
				(width 0.1524)
				(type default)
			)
			(layer "F.SilkS")
		)
		(fp_line
			(start -1.905 0.8636)
			(end -1.905 -0.8636)
			(stroke
				(width 0.1524)
				(type default)
			)
			(layer "F.SilkS")
		)
		(fp_line
			(start -1.905 -0.8636)
			(end 1.905 -0.8636)
			(stroke
				(width 0.1524)
				(type default)
			)
			(layer "F.SilkS")
		)
		(fp_rect
			(start -1.524 0.7366)
			(end 1.524 -0.7366)
			(stroke
				(width 0)
				(type default)
			)
			(fill no)
			(layer "F.CrtYd")
		)
		(pad "1" smd rect
			(at 0.94996 0 180)
			(size 1.1176 1.3716)
			(layers "F.Cu" "F.Mask" "F.Paste")
			(net "P3V3_NODE1")
		)
		(pad "2" smd rect
			(at -0.94996 0 180)
			(size 1.1176 1.3716)
			(layers "F.Cu" "F.Mask" "F.Paste")
			(net "GND")
		)
	)
	(footprint ""
		(layer "F.Cu")
		(at 149.462998 -142.88643 -90)
		(property "Reference" "R570"
			(at -1.397508 0.624332 90)
			(unlocked yes)
			(layer "F.SilkS")
			(effects
				(font
					(size 0.635 0.4064)
					(thickness 0.1524)
				)
				(justify left)
			)
		)
		(property "Value" ""
			(at 0 0 270)
			(layer "F.Fab")
			(effects
				(font
					(size 1.27 1.27)
				)
			)
		)
		(duplicate_pad_numbers_are_jumpers no)
		(fp_line
			(start -0.7874 0.4064)
			(end -0.7874 -0.4064)
			(stroke
				(width 0.1524)
				(type default)
			)
			(layer "F.SilkS")
		)
		(fp_line
			(start 0.7874 0.4064)
			(end -0.7874 0.4064)
			(stroke
				(width 0.1524)
				(type default)
			)
			(layer "F.SilkS")
		)
		(fp_line
			(start -0.7874 -0.4064)
			(end 0.7874 -0.4064)
			(stroke
				(width 0.1524)
				(type default)
			)
			(layer "F.SilkS")
		)
		(fp_line
			(start 0.7874 -0.4064)
			(end 0.7874 0.4064)
			(stroke
				(width 0.1524)
				(type default)
			)
			(layer "F.SilkS")
		)
		(fp_poly
			(pts
				(xy -0.508 0.2794) (xy -0.508 0.2286) (xy -0.635 0.2286) (xy -0.635 -0.254) (xy -0.5334 -0.254)
				(xy -0.5334 -0.2794) (xy 0.5334 -0.2794) (xy 0.5334 -0.254) (xy 0.635 -0.254) (xy 0.635 0.254) (xy 0.5334 0.254)
				(xy 0.5334 0.2794)
			)
			(stroke
				(width 0)
				(type default)
			)
			(fill no)
			(layer "F.CrtYd")
		)
		(pad "1" smd rect
			(at 0.40005 0 270)
			(size 0.4572 0.508)
			(layers "F.Cu" "F.Mask" "F.Paste")
			(net "P3V3_NODE1")
		)
		(pad "2" smd rect
			(at -0.40005 0 270)
			(size 0.4572 0.508)
			(layers "F.Cu" "F.Mask" "F.Paste")
			(net "SMB_LAN2_CLK")
		)
	)
)
